(kicad_pcb
	(version 20260206)
	(generator "pcbnew")
	(generator_version "10.0")
	(general
		(thickness 1.6)
		(legacy_teardrops no)
	)
	(paper "A4")
	(title_block
		(title "netronome-mezz — pcbd0082-001_rev01_jul9_a.brd")
		(comment 1 "Open CloudServer (Microsoft) / footprints 39-46 of 714")
	)
	(layers
		(0 "F.Cu" signal "TOP")
		(4 "In1.Cu" signal "02_GND")
		(6 "In2.Cu" signal "03_SIG")
		(8 "In3.Cu" signal "04_SIG")
		(10 "In4.Cu" signal "05_GND")
		(12 "In5.Cu" signal "06_PWR1")
		(14 "In6.Cu" signal "07_SIG")
		(16 "In7.Cu" signal "08_SIG")
		(18 "In8.Cu" signal "09_GND")
		(2 "B.Cu" signal "BOTTOM")
		(9 "F.Adhes" user "F.Adhesive")
		(11 "B.Adhes" user "B.Adhesive")
		(13 "F.Paste" user "Package Geometry/Pastemask Top")
		(15 "B.Paste" user "Package Geometry/Pastemask Bottom")
		(5 "F.SilkS" user "Ref Des/Silkscreen Top")
		(7 "B.SilkS" user "Ref Des/Silkscreen Bottom")
		(1 "F.Mask" user "Board Geometry/Soldermask Top")
		(3 "B.Mask" user "Board Geometry/Soldermask Bottom")
		(17 "Dwgs.User" user "User.Drawings")
		(19 "Cmts.User" user "User.Comments")
		(21 "Eco1.User" user "User.Eco1")
		(23 "Eco2.User" user "User.Eco2")
		(25 "Edge.Cuts" user "Board Geometry/Outline")
		(27 "Margin" user)
		(31 "F.CrtYd" user "Package Geometry/Place Bound Top")
		(29 "B.CrtYd" user "Package Geometry/Place Bound Bottom")
		(35 "F.Fab" user "Ref Des/Assembly Top")
		(33 "B.Fab" user "Ref Des/Assembly Bottom")
		(45 "User.4" user "COMPVAL_TYPE_BOTTOM")
	)
	(footprint ""
		(layer "F.Cu")
		(at 17.399 1.397)
		(property "Reference" "R73"
			(at 0.78867 -0.762 90)
			(unlocked yes)
			(layer "F.SilkS")
			(effects
				(font
					(size 0.7874 0.5842)
					(thickness 0.127)
				)
				(justify left)
			)
		)
		(property "Value" "4.75K"
			(at -0.148158 1.3462 90)
			(unlocked yes)
			(layer "F.Fab")
			(hide yes)
			(effects
				(font
					(size 1.27 0.9652)
					(thickness 0.000001)
				)
				(justify left)
			)
		)
		(property "Device Type" "REST4024"
			(at -0.148158 1.3462 90)
			(unlocked yes)
			(layer "F.Fab")
			(hide yes)
			(effects
				(font
					(size 1.27 0.9652)
					(thickness 0.000001)
				)
				(justify left)
			)
		)
		(duplicate_pad_numbers_are_jumpers no)
		(fp_poly
			(pts
				(xy 0.635 1.0668) (xy 0.635 -1.0668) (xy -0.635 -1.0668) (xy -0.635 1.0668)
			)
			(stroke
				(width 0)
				(type default)
			)
			(fill no)
			(layer "F.CrtYd")
		)
		(fp_line
			(start -0.254 -0.508)
			(end 0.254 -0.508)
			(stroke
				(width 0.0254)
				(type default)
			)
			(layer "F.Fab")
		)
		(fp_line
			(start -0.254 0.508)
			(end -0.254 -0.508)
			(stroke
				(width 0.0254)
				(type default)
			)
			(layer "F.Fab")
		)
		(fp_line
			(start 0.254 -0.508)
			(end 0.254 0.508)
			(stroke
				(width 0.0254)
				(type default)
			)
			(layer "F.Fab")
		)
		(fp_line
			(start 0.254 0.508)
			(end -0.254 0.508)
			(stroke
				(width 0.0254)
				(type default)
			)
			(layer "F.Fab")
		)
		(pad "1" smd rect
			(at 0 -0.4191)
			(size 0.508 0.5334)
			(layers "F.Cu" "F.Mask" "F.Paste")
			(net "EXT_3.3V")
		)
		(pad "2" smd rect
			(at 0 0.4191)
			(size 0.508 0.5334)
			(layers "F.Cu" "F.Mask" "F.Paste")
			(net "PCIE0_RST_L")
		)
		(zone
			(layer "F.Cu")
			(hatch none 0.5)
			(connect_pads
				(clearance 0)
			)
			(min_thickness 0.25)
			(keepout
				(tracks not_allowed)
				(vias allowed)
				(pads allowed)
				(copperpour not_allowed)
				(footprints allowed)
			)
			(placement
				(enabled no)
				(sheetname "")
			)
			(fill
				(thermal_gap 0.5)
				(thermal_bridge_width 0.5)
				(island_removal_mode 0)
			)
			(polygon
				(pts
					(xy 17.4244 1.3716) (xy 17.4244 1.4224) (xy 17.3736 1.4224) (xy 17.3736 1.3716)
				)
			)
		)
	)
	(footprint ""
		(layer "F.Cu")
		(at 65.024 36.957 -90)
		(property "Reference" "R166"
			(at -0.86233 2.667 0)
			(unlocked yes)
			(layer "F.SilkS")
			(effects
				(font
					(size 0.7874 0.5842)
					(thickness 0.127)
				)
				(justify left)
			)
		)
		(property "Value" "0"
			(at -0.148158 1.3462 0)
			(unlocked yes)
			(layer "F.Fab")
			(hide yes)
			(effects
				(font
					(size 1.27 0.9652)
					(thickness 0.000001)
				)
				(justify left)
			)
		)
		(property "Device Type" "REST1111"
			(at -0.148158 1.3462 0)
			(unlocked yes)
			(layer "F.Fab")
			(hide yes)
			(effects
				(font
					(size 1.27 0.9652)
					(thickness 0.000001)
				)
				(justify left)
			)
		)
		(duplicate_pad_numbers_are_jumpers no)
		(fp_poly
			(pts
				(xy 0.635 1.0668) (xy 0.635 -1.0668) (xy -0.635 -1.0668) (xy -0.635 1.0668)
			)
			(stroke
				(width 0)
				(type default)
			)
			(fill no)
			(layer "F.CrtYd")
		)
		(fp_line
			(start -0.254 0.508)
			(end -0.254 -0.508)
			(stroke
				(width 0.0254)
				(type default)
			)
			(layer "F.Fab")
		)
		(fp_line
			(start 0.254 0.508)
			(end -0.254 0.508)
			(stroke
				(width 0.0254)
				(type default)
			)
			(layer "F.Fab")
		)
		(fp_line
			(start -0.254 -0.508)
			(end 0.254 -0.508)
			(stroke
				(width 0.0254)
				(type default)
			)
			(layer "F.Fab")
		)
		(fp_line
			(start 0.254 -0.508)
			(end 0.254 0.508)
			(stroke
				(width 0.0254)
				(type default)
			)
			(layer "F.Fab")
		)
		(pad "1" smd rect
			(at 0 -0.4191 270)
			(size 0.508 0.5334)
			(layers "F.Cu" "F.Mask" "F.Paste")
			(net "VDD_CORE")
		)
		(pad "2" smd rect
			(at 0 0.4191 270)
			(size 0.508 0.5334)
			(layers "F.Cu" "F.Mask" "F.Paste")
			(net "NFP_VDD_CORE_ISEN1_N")
		)
		(zone
			(layer "F.Cu")
			(hatch none 0.5)
			(connect_pads
				(clearance 0)
			)
			(min_thickness 0.25)
			(keepout
				(tracks not_allowed)
				(vias allowed)
				(pads allowed)
				(copperpour not_allowed)
				(footprints allowed)
			)
			(placement
				(enabled no)
				(sheetname "")
			)
			(fill
				(thermal_gap 0.5)
				(thermal_bridge_width 0.5)
				(island_removal_mode 0)
			)
			(polygon
				(pts
					(xy 65.0494 36.9824) (xy 64.9986 36.9824) (xy 64.9986 36.9316) (xy 65.0494 36.9316)
				)
			)
		)
	)
	(footprint ""
		(layer "F.Cu")
		(at 17.78 47.498 180)
		(property "Reference" "TP50"
			(at 3.556 -2.05867 0)
			(unlocked yes)
			(layer "F.SilkS")
			(effects
				(font
					(size 0.7874 0.5842)
					(thickness 0.127)
				)
				(justify left)
			)
		)
		(property "Value" "*"
			(at -0.4826 -0.14732 180)
			(unlocked yes)
			(layer "F.Fab")
			(hide yes)
			(effects
				(font
					(size 1.27 0.9652)
					(thickness 0.000001)
				)
				(justify left)
			)
		)
		(property "Device Type" "TP_SMALL"
			(at -0.4826 -0.14732 180)
			(unlocked yes)
			(layer "F.Fab")
			(hide yes)
			(effects
				(font
					(size 1.27 0.9652)
					(thickness 0.000001)
				)
				(justify left)
			)
		)
		(duplicate_pad_numbers_are_jumpers no)
		(fp_line
			(start 0.8636 0.8636)
			(end 0.8636 -0.8636)
			(stroke
				(width 0.1524)
				(type default)
			)
			(layer "F.SilkS")
		)
		(fp_line
			(start 0.8636 -0.8636)
			(end -0.8636 -0.8636)
			(stroke
				(width 0.1524)
				(type default)
			)
			(layer "F.SilkS")
		)
		(fp_line
			(start -0.8636 0.8636)
			(end 0.8636 0.8636)
			(stroke
				(width 0.1524)
				(type default)
			)
			(layer "F.SilkS")
		)
		(fp_line
			(start -0.8636 -0.8636)
			(end -0.8636 0.8636)
			(stroke
				(width 0.1524)
				(type default)
			)
			(layer "F.SilkS")
		)
		(fp_poly
			(pts
				(xy -0.635 -0.635) (xy -0.635 0.635) (xy 0.635 0.635) (xy 0.635 -0.635)
			)
			(stroke
				(width 0)
				(type default)
			)
			(fill no)
			(layer "F.CrtYd")
		)
		(pad "1" smd rect
			(at 0 0 180)
			(size 1.27 1.27)
			(layers "F.Cu" "F.Mask" "F.Paste")
			(net "VDD_1.8V")
		)
	)
	(footprint ""
		(layer "F.Cu")
		(at 16.383 42.2021 -90)
		(property "Reference" "C19"
			(at -0.13843 3.683 0)
			(unlocked yes)
			(layer "F.SilkS")
			(effects
				(font
					(size 0.7874 0.5842)
					(thickness 0.127)
				)
				(justify left)
			)
		)
		(property "Value" "22UF"
			(at -0.148158 1.7526 0)
			(unlocked yes)
			(layer "F.Fab")
			(hide yes)
			(effects
				(font
					(size 1.27 0.9652)
					(thickness 0.000001)
				)
				(justify left)
			)
		)
		(property "Device Type" "CAPC0063"
			(at -0.148158 1.7526 0)
			(unlocked yes)
			(layer "F.Fab")
			(hide yes)
			(effects
				(font
					(size 1.27 0.9652)
					(thickness 0.000001)
				)
				(justify left)
			)
		)
		(duplicate_pad_numbers_are_jumpers no)
		(fp_circle
			(center 0 0)
			(end 0 -0.127)
			(stroke
				(width 0.2032)
				(type default)
			)
			(fill no)
			(layer "F.SilkS")
		)
		(fp_poly
			(pts
				(xy 0.7874 -1.6637) (xy -0.7874 -1.6637) (xy -0.7874 1.6637) (xy 0.7874 1.6637)
			)
			(stroke
				(width 0)
				(type default)
			)
			(fill no)
			(layer "F.CrtYd")
		)
		(fp_line
			(start -0.4064 0.8128)
			(end -0.4064 -0.7874)
			(stroke
				(width 0.0254)
				(type default)
			)
			(layer "F.Fab")
		)
		(fp_line
			(start 0.4064 0.8128)
			(end -0.4064 0.8128)
			(stroke
				(width 0.0254)
				(type default)
			)
			(layer "F.Fab")
		)
		(fp_line
			(start -0.4064 -0.7874)
			(end 0.4064 -0.7874)
			(stroke
				(width 0.0254)
				(type default)
			)
			(layer "F.Fab")
		)
		(fp_line
			(start 0.4064 -0.7874)
			(end 0.4064 0.8128)
			(stroke
				(width 0.0254)
				(type default)
			)
			(layer "F.Fab")
		)
		(pad "1" smd rect
			(at 0 -0.8001 270)
			(size 0.8636 0.9652)
			(layers "F.Cu" "F.Mask" "F.Paste")
			(net "VDD_1.8V")
		)
		(pad "2" smd rect
			(at 0 0.8001 270)
			(size 0.8636 0.9652)
			(layers "F.Cu" "F.Mask" "F.Paste")
			(net "GND")
		)
		(zone
			(layer "F.Cu")
			(hatch none 0.5)
			(connect_pads
				(clearance 0)
			)
			(min_thickness 0.25)
			(keepout
				(tracks not_allowed)
				(vias allowed)
				(pads allowed)
				(copperpour not_allowed)
				(footprints allowed)
			)
			(placement
				(enabled no)
				(sheetname "")
			)
			(fill
				(thermal_gap 0.5)
				(thermal_bridge_width 0.5)
				(island_removal_mode 0)
			)
			(polygon
				(pts
					(xy 16.637 42.1386) (xy 16.637 42.2656) (xy 16.129 42.2656) (xy 16.129 42.1386)
				)
			)
		)
	)
	(footprint ""
		(layer "F.Cu")
		(at 73.05101 19.055994)
		(property "Reference" "V_A-DQ25"
			(at 0 0 0)
			(layer "F.SilkS")
			(hide yes)
			(effects
				(font
					(size 1.27 1.27)
				)
			)
		)
		(property "Value" ""
			(at 0 0 0)
			(layer "F.Fab")
			(effects
				(font
					(size 1.27 1.27)
				)
			)
		)
		(duplicate_pad_numbers_are_jumpers no)
		(pad "1" thru_hole circle
			(at 0 0)
			(size 0.762 0.762)
			(drill 0.20574)
			(layers "*.Cu" "*.Mask")
			(remove_unused_layers no)
			(net "DDR0_32A_DQ25")
			(clearance 0.127)
			(thermal_gap 0.127)
			(padstack
				(mode front_inner_back)
				(layer "Inner"
					(shape circle)
					(size 0.4572 0.4572)
					(clearance 0.1143)
				)
				(layer "B.Cu"
					(shape circle)
					(size 0.4572 0.4572)
					(clearance 0.1143)
				)
			)
		)
	)
	(footprint ""
		(layer "F.Cu")
		(at 19.685 6.5278)
		(property "Reference" "R393"
			(at 0 0 0)
			(layer "F.SilkS")
			(hide yes)
			(effects
				(font
					(size 1.27 1.27)
				)
			)
		)
		(property "Value" "240"
			(at -0.148158 1.3462 90)
			(unlocked yes)
			(layer "F.Fab")
			(hide yes)
			(effects
				(font
					(size 1.27 0.9652)
					(thickness 0.000001)
				)
				(justify left)
			)
		)
		(property "Device Type" "REST0009"
			(at -0.148158 1.3462 90)
			(unlocked yes)
			(layer "F.Fab")
			(hide yes)
			(effects
				(font
					(size 1.27 0.9652)
					(thickness 0.000001)
				)
				(justify left)
			)
		)
		(duplicate_pad_numbers_are_jumpers no)
		(fp_poly
			(pts
				(xy 0.635 1.0668) (xy 0.635 -1.0668) (xy -0.635 -1.0668) (xy -0.635 1.0668)
			)
			(stroke
				(width 0)
				(type default)
			)
			(fill no)
			(layer "F.CrtYd")
		)
		(fp_line
			(start -0.254 -0.508)
			(end 0.254 -0.508)
			(stroke
				(width 0.0254)
				(type default)
			)
			(layer "F.Fab")
		)
		(fp_line
			(start -0.254 0.508)
			(end -0.254 -0.508)
			(stroke
				(width 0.0254)
				(type default)
			)
			(layer "F.Fab")
		)
		(fp_line
			(start 0.254 -0.508)
			(end 0.254 0.508)
			(stroke
				(width 0.0254)
				(type default)
			)
			(layer "F.Fab")
		)
		(fp_line
			(start 0.254 0.508)
			(end -0.254 0.508)
			(stroke
				(width 0.0254)
				(type default)
			)
			(layer "F.Fab")
		)
		(pad "1" smd rect
			(at 0 -0.4191)
			(size 0.508 0.5334)
			(layers "F.Cu" "F.Mask" "F.Paste")
			(net "13N4321")
		)
		(pad "2" smd rect
			(at 0 0.4191)
			(size 0.508 0.5334)
			(layers "F.Cu" "F.Mask" "F.Paste")
			(net "VDD_3.3V")
		)
		(zone
			(layer "F.Cu")
			(hatch none 0.5)
			(connect_pads
				(clearance 0)
			)
			(min_thickness 0.25)
			(keepout
				(tracks not_allowed)
				(vias allowed)
				(pads allowed)
				(copperpour not_allowed)
				(footprints allowed)
			)
			(placement
				(enabled no)
				(sheetname "")
			)
			(fill
				(thermal_gap 0.5)
				(thermal_bridge_width 0.5)
				(island_removal_mode 0)
			)
			(polygon
				(pts
					(xy 19.7104 6.5024) (xy 19.7104 6.5532) (xy 19.6596 6.5532) (xy 19.6596 6.5024)
				)
			)
		)
	)
	(footprint ""
		(layer "F.Cu")
		(at 75.451005 13.456006)
		(property "Reference" "V_A-DQ21"
			(at 0 0 0)
			(layer "F.SilkS")
			(hide yes)
			(effects
				(font
					(size 1.27 1.27)
				)
			)
		)
		(property "Value" ""
			(at 0 0 0)
			(layer "F.Fab")
			(effects
				(font
					(size 1.27 1.27)
				)
			)
		)
		(duplicate_pad_numbers_are_jumpers no)
		(pad "1" thru_hole circle
			(at 0 0)
			(size 0.762 0.762)
			(drill 0.20574)
			(layers "*.Cu" "*.Mask")
			(remove_unused_layers no)
			(net "DDR0_32A_DQ21")
			(clearance 0.127)
			(thermal_gap 0.127)
			(padstack
				(mode front_inner_back)
				(layer "Inner"
					(shape circle)
					(size 0.4572 0.4572)
					(clearance 0.1143)
				)
				(layer "B.Cu"
					(shape circle)
					(size 0.4572 0.4572)
					(clearance 0.1143)
				)
			)
		)
	)
	(footprint ""
		(layer "F.Cu")
		(at 17.653 12.192 180)
		(property "Reference" "R350"
			(at -0.02667 -3.937 90)
			(unlocked yes)
			(layer "F.SilkS")
			(effects
				(font
					(size 0.7874 0.5842)
					(thickness 0.127)
				)
				(justify left)
			)
		)
		(property "Value" "0"
			(at -0.148158 1.3462 270)
			(unlocked yes)
			(layer "F.Fab")
			(hide yes)
			(effects
				(font
					(size 1.27 0.9652)
					(thickness 0.000001)
				)
				(justify left)
			)
		)
		(property "Device Type" "REST1111"
			(at -0.148158 1.3462 270)
			(unlocked yes)
			(layer "F.Fab")
			(hide yes)
			(effects
				(font
					(size 1.27 0.9652)
					(thickness 0.000001)
				)
				(justify left)
			)
		)
		(duplicate_pad_numbers_are_jumpers no)
		(fp_poly
			(pts
				(xy 0.635 1.0668) (xy 0.635 -1.0668) (xy -0.635 -1.0668) (xy -0.635 1.0668)
			)
			(stroke
				(width 0)
				(type default)
			)
			(fill no)
			(layer "F.CrtYd")
		)
		(fp_line
			(start 0.254 0.508)
			(end -0.254 0.508)
			(stroke
				(width 0.0254)
				(type default)
			)
			(layer "F.Fab")
		)
		(fp_line
			(start 0.254 -0.508)
			(end 0.254 0.508)
			(stroke
				(width 0.0254)
				(type default)
			)
			(layer "F.Fab")
		)
		(fp_line
			(start -0.254 0.508)
			(end -0.254 -0.508)
			(stroke
				(width 0.0254)
				(type default)
			)
			(layer "F.Fab")
		)
		(fp_line
			(start -0.254 -0.508)
			(end 0.254 -0.508)
			(stroke
				(width 0.0254)
				(type default)
			)
			(layer "F.Fab")
		)
		(pad "1" smd rect
			(at 0 -0.4191 180)
			(size 0.508 0.5334)
			(layers "F.Cu" "F.Mask" "F.Paste")
			(net "CPLD_SMBUS_SDA")
		)
		(pad "2" smd rect
			(at 0 0.4191 180)
			(size 0.508 0.5334)
			(layers "F.Cu" "F.Mask" "F.Paste")
			(net "SMBUS_SDA")
		)
		(zone
			(layer "F.Cu")
			(hatch none 0.5)
			(connect_pads
				(clearance 0)
			)
			(min_thickness 0.25)
			(keepout
				(tracks not_allowed)
				(vias allowed)
				(pads allowed)
				(copperpour not_allowed)
				(footprints allowed)
			)
			(placement
				(enabled no)
				(sheetname "")
			)
			(fill
				(thermal_gap 0.5)
				(thermal_bridge_width 0.5)
				(island_removal_mode 0)
			)
			(polygon
				(pts
					(xy 17.6276 12.2174) (xy 17.6276 12.1666) (xy 17.6784 12.1666) (xy 17.6784 12.2174)
				)
			)
		)
	)
)
